(kicad_pcb
	(version 20260206)
	(generator "pcbnew")
	(generator_version "10.0")
	(general
		(thickness 1.6)
		(legacy_teardrops no)
	)
	(paper "A4")
	(title_block
		(title "04192023_DAF0TMB3IC0_F0TG_MB_C_brd_V02_OCP.brd")
		(comment 1 "Grand Teton / footprints 4638-4640 of 8354")
	)
	(layers
		(0 "F.Cu" signal "TOP")
		(4 "In1.Cu" signal "GND")
		(6 "In2.Cu" signal "IN1")
		(8 "In3.Cu" signal "GND1")
		(10 "In4.Cu" signal "IN2")
		(12 "In5.Cu" signal "GND2")
		(14 "In6.Cu" signal "IN3")
		(16 "In7.Cu" signal "GND3")
		(18 "In8.Cu" signal "VCC")
		(20 "In9.Cu" signal "VCC1")
		(22 "In10.Cu" signal "GND4")
		(24 "In11.Cu" signal "IN4")
		(26 "In12.Cu" signal "GND5")
		(28 "In13.Cu" signal "IN5")
		(30 "In14.Cu" signal "GND6")
		(32 "In15.Cu" signal "IN6")
		(34 "In16.Cu" signal "GND7")
		(2 "B.Cu" signal "BOTTOM")
		(9 "F.Adhes" user "F.Adhesive")
		(11 "B.Adhes" user "B.Adhesive")
		(13 "F.Paste" user "Package Geometry/Pastemask Top")
		(15 "B.Paste" user "Package Geometry/Pastemask Bottom")
		(5 "F.SilkS" user "Ref Des/Silkscreen Top")
		(7 "B.SilkS" user "Ref Des/Silkscreen Bottom")
		(1 "F.Mask" user "Board Geometry/Soldermask Top")
		(3 "B.Mask" user "Board Geometry/Soldermask Bottom")
		(17 "Dwgs.User" user "User.Drawings")
		(19 "Cmts.User" user "User.Comments")
		(21 "Eco1.User" user "User.Eco1")
		(23 "Eco2.User" user "User.Eco2")
		(25 "Edge.Cuts" user "Board Geometry/Outline")
		(27 "Margin" user)
		(31 "F.CrtYd" user "Package Geometry/Place Bound Top")
		(29 "B.CrtYd" user "Package Geometry/Place Bound Bottom")
		(35 "F.Fab" user "Ref Des/Assembly Top")
		(33 "B.Fab" user "Ref Des/Assembly Bottom")
	)
	(footprint ""
		(layer "F.Cu")
		(at 105.659936 -119.479568 90)
		(property "Reference" "R1449"
			(at 0 0 90)
			(layer "F.SilkS")
			(hide yes)
			(effects
				(font
					(size 1.27 1.27)
				)
			)
		)
		(property "Value" ""
			(at 0 0 90)
			(layer "F.Fab")
			(effects
				(font
					(size 1.27 1.27)
				)
			)
		)
		(duplicate_pad_numbers_are_jumpers no)
		(fp_line
			(start 0.7874 -0.4064)
			(end 0.7874 0.4064)
			(stroke
				(width 0.1524)
				(type default)
			)
			(layer "F.SilkS")
		)
		(fp_line
			(start -0.7874 -0.4064)
			(end 0.7874 -0.4064)
			(stroke
				(width 0.1524)
				(type default)
			)
			(layer "F.SilkS")
		)
		(fp_line
			(start 0.7874 0.4064)
			(end -0.7874 0.4064)
			(stroke
				(width 0.1524)
				(type default)
			)
			(layer "F.SilkS")
		)
		(fp_line
			(start -0.7874 0.4064)
			(end -0.7874 -0.4064)
			(stroke
				(width 0.1524)
				(type default)
			)
			(layer "F.SilkS")
		)
		(fp_line
			(start -0.12065 -0.305054)
			(end -0.12065 -0.2794)
			(stroke
				(width 0.1)
				(type default)
			)
			(layer "F.Fab")
		)
		(fp_line
			(start -0.67945 -0.305054)
			(end -0.12065 -0.305054)
			(stroke
				(width 0.1)
				(type default)
			)
			(layer "F.Fab")
		)
		(fp_line
			(start 0.67945 -0.3048)
			(end 0.67945 0.3048)
			(stroke
				(width 0.1)
				(type default)
			)
			(layer "F.Fab")
		)
		(fp_line
			(start 0.12065 -0.3048)
			(end 0.67945 -0.3048)
			(stroke
				(width 0.1)
				(type default)
			)
			(layer "F.Fab")
		)
		(fp_line
			(start 0.12065 -0.2794)
			(end 0.12065 -0.3048)
			(stroke
				(width 0.1)
				(type default)
			)
			(layer "F.Fab")
		)
		(fp_line
			(start -0.12065 -0.2794)
			(end 0.12065 -0.2794)
			(stroke
				(width 0.1)
				(type default)
			)
			(layer "F.Fab")
		)
		(fp_line
			(start 0.120396 0.2794)
			(end -0.12065 0.2794)
			(stroke
				(width 0.1)
				(type default)
			)
			(layer "F.Fab")
		)
		(fp_line
			(start -0.12065 0.2794)
			(end -0.12065 0.3048)
			(stroke
				(width 0.1)
				(type default)
			)
			(layer "F.Fab")
		)
		(fp_line
			(start 0.67945 0.3048)
			(end 0.120396 0.3048)
			(stroke
				(width 0.1)
				(type default)
			)
			(layer "F.Fab")
		)
		(fp_line
			(start 0.120396 0.3048)
			(end 0.120396 0.2794)
			(stroke
				(width 0.1)
				(type default)
			)
			(layer "F.Fab")
		)
		(fp_line
			(start -0.12065 0.3048)
			(end -0.67945 0.3048)
			(stroke
				(width 0.1)
				(type default)
			)
			(layer "F.Fab")
		)
		(fp_line
			(start -0.67945 0.3048)
			(end -0.67945 -0.305054)
			(stroke
				(width 0.1)
				(type default)
			)
			(layer "F.Fab")
		)
		(pad "1" smd circle
			(at -0.40005 0 90)
			(size 0 0)
			(layers "F.Cu" "F.Mask" "F.Paste")
			(net "P3V3_AUX")
		)
		(pad "2" smd circle
			(at 0.40005 0 90)
			(size 0 0)
			(layers "F.Cu" "F.Mask" "F.Paste")
			(net "PWRGD_P12V_MEM_CPU1_EN_N")
		)
	)
	(footprint ""
		(layer "F.Cu")
		(at 331.58303 -20.397978)
		(property "Reference" "Q28"
			(at -3.251962 1.45542 90)
			(unlocked yes)
			(layer "F.SilkS")
			(effects
				(font
					(size 0.7874 0.5842)
					(thickness 0.1524)
				)
				(justify left)
			)
		)
		(property "Value" ""
			(at 0 0 0)
			(layer "F.Fab")
			(effects
				(font
					(size 1.27 1.27)
				)
			)
		)
		(duplicate_pad_numbers_are_jumpers no)
		(fp_line
			(start -1.332738 -1.100074)
			(end -0.4826 -1.100074)
			(stroke
				(width 0.1524)
				(type default)
			)
			(layer "F.SilkS")
		)
		(fp_line
			(start -1.332738 1.100074)
			(end -1.332738 -1.100074)
			(stroke
				(width 0.1524)
				(type default)
			)
			(layer "F.SilkS")
		)
		(fp_line
			(start -0.4826 -1.100074)
			(end 0 -0.541274)
			(stroke
				(width 0.1524)
				(type default)
			)
			(layer "F.SilkS")
		)
		(fp_line
			(start 0 -0.541274)
			(end 0.4826 -1.100074)
			(stroke
				(width 0.1524)
				(type default)
			)
			(layer "F.SilkS")
		)
		(fp_line
			(start 0.4826 -1.100074)
			(end 1.332738 -1.100074)
			(stroke
				(width 0.1524)
				(type default)
			)
			(layer "F.SilkS")
		)
		(fp_line
			(start 1.332738 -1.100074)
			(end 1.332738 1.100074)
			(stroke
				(width 0.1524)
				(type default)
			)
			(layer "F.SilkS")
		)
		(fp_line
			(start 1.332738 1.100074)
			(end -1.332738 1.100074)
			(stroke
				(width 0.1524)
				(type default)
			)
			(layer "F.SilkS")
		)
		(fp_poly
			(pts
				(xy -1.533144 -0.649986) (xy -2.2352 -0.298958) (xy -2.2352 -1.001014)
			)
			(stroke
				(width 0)
				(type default)
			)
			(fill yes)
			(layer "F.SilkS")
		)
		(fp_line
			(start -0.674878 -1.100074)
			(end 0.674878 -1.100074)
			(stroke
				(width 0.1)
				(type default)
			)
			(layer "F.Fab")
		)
		(fp_line
			(start -0.674878 1.100074)
			(end -0.674878 -1.100074)
			(stroke
				(width 0.1)
				(type default)
			)
			(layer "F.Fab")
		)
		(fp_line
			(start 0.674878 -1.100074)
			(end 0.674878 1.100074)
			(stroke
				(width 0.1)
				(type default)
			)
			(layer "F.Fab")
		)
		(fp_line
			(start 0.674878 1.100074)
			(end -0.674878 1.100074)
			(stroke
				(width 0.1)
				(type default)
			)
			(layer "F.Fab")
		)
		(fp_poly
			(pts
				(xy -2.2352 -0.298958) (xy -2.2352 -1.001014) (xy -1.533144 -0.649986)
			)
			(stroke
				(width 0)
				(type default)
			)
			(fill yes)
			(layer "F.Fab")
		)
		(pad "1" smd rect
			(at -0.94996 -0.649986 90)
			(size 0.4318 0.508)
			(layers "F.Cu" "F.Mask" "F.Paste")
			(net "GND")
		)
		(pad "2" smd rect
			(at -0.94996 0 90)
			(size 0.4318 0.508)
			(layers "F.Cu" "F.Mask" "F.Paste")
			(net "BMC_FPGA_LED1")
		)
		(pad "3" smd rect
			(at -0.94996 0.649986 90)
			(size 0.4318 0.508)
			(layers "F.Cu" "F.Mask" "F.Paste")
			(net "BMC_FPGA_LED2_N")
		)
		(pad "4" smd rect
			(at 0.94996 0.649986 90)
			(size 0.4318 0.508)
			(layers "F.Cu" "F.Mask" "F.Paste")
			(net "GND")
		)
		(pad "5" smd rect
			(at 0.94996 0 90)
			(size 0.4318 0.508)
			(layers "F.Cu" "F.Mask" "F.Paste")
			(net "BMC_FPGA_LED2")
		)
		(pad "6" smd rect
			(at 0.94996 -0.649986 90)
			(size 0.4318 0.508)
			(layers "F.Cu" "F.Mask" "F.Paste")
			(net "BMC_FPGA_LED1_N")
		)
	)
	(footprint ""
		(layer "F.Cu")
		(at 377.909582 -416.899344 -90)
		(property "Reference" "C6569"
			(at 0 0 270)
			(layer "F.SilkS")
			(hide yes)
			(effects
				(font
					(size 1.27 1.27)
				)
			)
		)
		(property "Value" ""
			(at 0 0 270)
			(layer "F.Fab")
			(effects
				(font
					(size 1.27 1.27)
				)
			)
		)
		(duplicate_pad_numbers_are_jumpers no)
		(fp_line
			(start -0.299974 0.150114)
			(end -0.299974 -0.150114)
			(stroke
				(width 0.1)
				(type default)
			)
			(layer "F.Fab")
		)
		(fp_line
			(start 0.299974 0.150114)
			(end -0.299974 0.150114)
			(stroke
				(width 0.1)
				(type default)
			)
			(layer "F.Fab")
		)
		(fp_line
			(start -0.299974 -0.150114)
			(end 0.299974 -0.150114)
			(stroke
				(width 0.1)
				(type default)
			)
			(layer "F.Fab")
		)
		(fp_line
			(start 0.299974 -0.150114)
			(end 0.299974 0.150114)
			(stroke
				(width 0.1)
				(type default)
			)
			(layer "F.Fab")
		)
		(pad "1" smd rect
			(at -0.2667 0 270)
			(size 0.3048 0.381)
			(layers "F.Cu" "F.Mask" "F.Paste")
			(net "P5E_CPU0_P2_TX_BUF_C_DP<2>")
		)
		(pad "2" smd rect
			(at 0.2667 0 270)
			(size 0.3048 0.381)
			(layers "F.Cu" "F.Mask" "F.Paste")
			(net "P5E_CPU0_P2_TX_BUF_DP<2>")
		)
	)
)
